(kicad_pcb
	(version 20241229)
	(generator "pcbnew")
	(generator_version "9.0")
	(general
		(thickness 1.294)
		(legacy_teardrops no)
	)
	(paper "A3")
	(title_block
		(title "Kintex 410T devboard")
		(date "2024-04-03")
		(rev "1.1.2")
		(comment 9 "footprints 136-141 of 975")
	)
	(layers
		(0 "F.Cu" mixed)
		(4 "In1.Cu" power)
		(6 "In2.Cu" power)
		(8 "In3.Cu" mixed)
		(10 "In4.Cu" power)
		(12 "In5.Cu" mixed)
		(14 "In6.Cu" power)
		(16 "In7.Cu" mixed)
		(18 "In8.Cu" power)
		(2 "B.Cu" mixed)
		(9 "F.Adhes" user "F.Adhesive")
		(11 "B.Adhes" user "B.Adhesive")
		(13 "F.Paste" user)
		(15 "B.Paste" user)
		(5 "F.SilkS" user "F.Silkscreen")
		(7 "B.SilkS" user "B.Silkscreen")
		(1 "F.Mask" user)
		(3 "B.Mask" user)
		(17 "Dwgs.User" user "User.Drawings")
		(19 "Cmts.User" user "User.Comments")
		(21 "Eco1.User" user "User.Eco1")
		(23 "Eco2.User" user "User.Eco2")
		(25 "Edge.Cuts" user)
		(27 "Margin" user)
		(31 "F.CrtYd" user "F.Courtyard")
		(29 "B.CrtYd" user "B.Courtyard")
		(35 "F.Fab" user)
		(33 "B.Fab" user)
	)
	(footprint "antmicro-footprints:SOT-23-6"
		(layer "F.Cu")
		(at 167.55 187.05)
		(property "Reference" "U36"
			(at -1.15 -2.05 0)
			(layer "F.SilkS")
			(effects
				(font
					(size 0.7 0.7)
					(thickness 0.15)
				)
				(justify left bottom)
			)
		)
		(property "Value" "LM3880"
			(at -1.75 2.75 0)
			(layer "F.Fab")
			(effects
				(font
					(size 0.7 0.7)
					(thickness 0.15)
				)
				(justify left bottom)
			)
		)
		(property "Description" "Power sequencer"
			(at 0 0 0)
			(layer "F.Fab")
			(hide yes)
			(effects
				(font
					(size 1.27 1.27)
					(thickness 0.15)
				)
			)
		)
		(property "Author" "Antmicro"
			(at 0 0 0)
			(layer "F.Fab")
			(hide yes)
			(effects
				(font
					(size 1 1)
					(thickness 0.15)
				)
			)
		)
		(property "License" "Apache-2.0"
			(at 0 0 0)
			(layer "F.Fab")
			(hide yes)
			(effects
				(font
					(size 1 1)
					(thickness 0.15)
				)
			)
		)
		(property "MPN" "LM3880MFX-1AA/NOPB"
			(at 0 0 0)
			(layer "F.Fab")
			(hide yes)
			(effects
				(font
					(size 1 1)
					(thickness 0.15)
				)
			)
		)
		(property "Manufacturer" "Texas Instruments"
			(at 0 0 0)
			(layer "F.Fab")
			(hide yes)
			(effects
				(font
					(size 1 1)
					(thickness 0.15)
				)
			)
		)
		(sheetname "DC-DC Converters")
		(sheetfile "dc-dc.kicad_sch")
		(attr smd)
		(fp_line
			(start -1.45 -0.7)
			(end -1.45 -0.4)
			(stroke
				(width 0.12)
				(type solid)
			)
			(layer "F.SilkS")
		)
		(fp_line
			(start -1.45 0.7)
			(end -1.45 0.4)
			(stroke
				(width 0.12)
				(type solid)
			)
			(layer "F.SilkS")
		)
		(fp_line
			(start -1.3 -0.7)
			(end -1.45 -0.7)
			(stroke
				(width 0.12)
				(type solid)
			)
			(layer "F.SilkS")
		)
		(fp_line
			(start 1.3 -0.7)
			(end 1.45 -0.7)
			(stroke
				(width 0.12)
				(type solid)
			)
			(layer "F.SilkS")
		)
		(fp_line
			(start 1.3 0.7)
			(end 1.45 0.7)
			(stroke
				(width 0.12)
				(type solid)
			)
			(layer "F.SilkS")
		)
		(fp_line
			(start 1.45 -0.7)
			(end 1.45 -0.4)
			(stroke
				(width 0.12)
				(type solid)
			)
			(layer "F.SilkS")
		)
		(fp_line
			(start 1.45 0.7)
			(end 1.45 0.4)
			(stroke
				(width 0.12)
				(type solid)
			)
			(layer "F.SilkS")
		)
		(fp_rect
			(start -1.55 -1.85)
			(end 1.55 1.75)
			(stroke
				(width 0.05)
				(type solid)
			)
			(fill no)
			(layer "F.CrtYd")
		)
		(fp_line
			(start -1.5 -0.7)
			(end 1.5 -0.7)
			(stroke
				(width 0.1)
				(type solid)
			)
			(layer "F.Fab")
		)
		(fp_line
			(start -1.5 0.7)
			(end -1.5 -0.7)
			(stroke
				(width 0.1)
				(type solid)
			)
			(layer "F.Fab")
		)
		(fp_line
			(start 1.5 -0.7)
			(end 1.5 0.7)
			(stroke
				(width 0.1)
				(type solid)
			)
			(layer "F.Fab")
		)
		(fp_line
			(start 1.5 0.7)
			(end -1.5 0.7)
			(stroke
				(width 0.1)
				(type solid)
			)
			(layer "F.Fab")
		)
		(fp_text user "."
			(at -1.4 1.2 180)
			(layer "F.SilkS")
			(effects
				(font
					(size 1 1)
					(thickness 0.15)
				)
			)
		)
		(pad "1" smd roundrect
			(at -0.954 1.1)
			(size 0.55 1)
			(layers "F.Cu" "F.Mask" "F.Paste")
			(roundrect_rratio 0.15)
			(net 37 "+3V3_AON")
			(pinfunction "VCC")
			(pintype "power_in")
		)
		(pad "2" smd roundrect
			(at -0.003 1.1)
			(size 0.55 1)
			(layers "F.Cu" "F.Mask" "F.Paste")
			(roundrect_rratio 0.15)
			(net 1 "GND")
			(pinfunction "GND")
			(pintype "power_in")
		)
		(pad "3" smd roundrect
			(at 0.947 1.1)
			(size 0.55 1)
			(layers "F.Cu" "F.Mask" "F.Paste")
			(roundrect_rratio 0.15)
			(net 14 "/DC-DC Converters/SEQ_EN")
			(pinfunction "EN")
			(pintype "input")
		)
		(pad "4" smd roundrect
			(at 0.947 -1.214)
			(size 0.55 1)
			(layers "F.Cu" "F.Mask" "F.Paste")
			(roundrect_rratio 0.15)
			(net 968 "/DC-DC Converters/EN3")
			(pinfunction "FLAG3")
			(pintype "open_collector")
		)
		(pad "5" smd roundrect
			(at -0.003 -1.214)
			(size 0.55 1)
			(layers "F.Cu" "F.Mask" "F.Paste")
			(roundrect_rratio 0.15)
			(net 967 "/DC-DC Converters/EN2")
			(pinfunction "FLAG2")
			(pintype "open_collector")
		)
		(pad "6" smd roundrect
			(at -0.954 -1.214)
			(size 0.55 1)
			(layers "F.Cu" "F.Mask" "F.Paste")
			(roundrect_rratio 0.15)
			(net 966 "/DC-DC Converters/EN1")
			(pinfunction "FLAG1")
			(pintype "open_collector")
		)
	)
	(footprint "antmicro-footprints:MP_Pad6mm_Drill3mm"
		(layer "F.Cu")
		(at 266.5 73.5)
		(property "Reference" "MH3"
			(at -0.178 4.025 0)
			(layer "F.SilkS")
			(hide yes)
			(effects
				(font
					(size 0.7 0.7)
					(thickness 0.15)
				)
				(justify left bottom)
			)
		)
		(property "Value" "MP_Pad6mm_Drill3mm"
			(at -0.153 -4.153 0)
			(layer "F.Fab")
			(effects
				(font
					(size 0.7 0.7)
					(thickness 0.15)
				)
				(justify left bottom)
			)
		)
		(property "Description" "Mechanical part"
			(at 0 0 0)
			(layer "F.Fab")
			(hide yes)
			(effects
				(font
					(size 1.27 1.27)
					(thickness 0.15)
				)
			)
		)
		(property "Author" "Antmicro"
			(at 0 0 0)
			(layer "F.Fab")
			(hide yes)
			(effects
				(font
					(size 1 1)
					(thickness 0.15)
				)
			)
		)
		(property "License" "Apache-2.0"
			(at 0 0 0)
			(layer "F.Fab")
			(hide yes)
			(effects
				(font
					(size 1 1)
					(thickness 0.15)
				)
			)
		)
		(property "MPN" ""
			(at 0 0 0)
			(layer "F.Fab")
			(hide yes)
			(effects
				(font
					(size 1 1)
					(thickness 0.15)
				)
			)
		)
		(property "Manufacturer" ""
			(at 0 0 0)
			(layer "F.Fab")
			(hide yes)
			(effects
				(font
					(size 1 1)
					(thickness 0.15)
				)
			)
		)
		(property "exclude_from_bom" ""
			(at 0 0 0)
			(layer "F.Fab")
			(hide yes)
			(effects
				(font
					(size 1 1)
					(thickness 0.15)
				)
			)
		)
		(sheetfile "k410t-devboard.kicad_sch")
		(attr exclude_from_pos_files exclude_from_bom)
		(pad "1" thru_hole circle
			(at 0 0)
			(size 6 6)
			(drill 3)
			(layers "*.Cu" "*.Mask")
			(remove_unused_layers no)
			(net 1 "GND")
			(pintype "passive")
		)
	)
	(footprint "antmicro-footprints:TP_SMD_0.75mm"
		(layer "F.Cu")
		(at 175.66 81.1308 180)
		(property "Reference" "TP2"
			(at -0.34 0.3308 270)
			(layer "F.SilkS")
			(effects
				(font
					(size 0.7 0.7)
					(thickness 0.15)
				)
				(justify left bottom)
			)
		)
		(property "Value" "TP_0.75mm_SMD"
			(at 0 1.2 180)
			(layer "F.Fab")
			(effects
				(font
					(size 0.7 0.7)
					(thickness 0.15)
				)
				(justify left bottom)
			)
		)
		(property "Description" "SMT test point"
			(at 0 0 180)
			(layer "F.Fab")
			(hide yes)
			(effects
				(font
					(size 1.27 1.27)
					(thickness 0.15)
				)
			)
		)
		(property "Author" "Antmicro"
			(at 351.32 162.2616 0)
			(layer "F.Fab")
			(hide yes)
			(effects
				(font
					(size 1 1)
					(thickness 0.15)
				)
			)
		)
		(property "License" "Apache-2.0"
			(at 351.32 162.2616 0)
			(layer "F.Fab")
			(hide yes)
			(effects
				(font
					(size 1 1)
					(thickness 0.15)
				)
			)
		)
		(property "MPN" ""
			(at 351.32 162.2616 0)
			(layer "F.Fab")
			(hide yes)
			(effects
				(font
					(size 1 1)
					(thickness 0.15)
				)
			)
		)
		(property "Manufacturer" ""
			(at 351.32 162.2616 0)
			(layer "F.Fab")
			(hide yes)
			(effects
				(font
					(size 1 1)
					(thickness 0.15)
				)
			)
		)
		(sheetname "FMC+ HSPC")
		(sheetfile "fmc-hspc.kicad_sch")
		(attr exclude_from_pos_files)
		(pad "1" smd circle
			(at 0 0 180)
			(size 0.75 0.75)
			(layers "F.Cu" "F.Mask")
			(net 216 "Net-(J18A-VREF_B_M2C)")
			(pinfunction "1")
			(pintype "passive")
		)
	)
	(footprint "antmicro-footprints:R_0402_1005Metric"
		(layer "F.Cu")
		(at 211.9 154.71 -90)
		(descr "Resistor SMD 0402")
		(tags "resistor SMD 0402")
		(property "Reference" "R85"
			(at -0.96 0.35 270)
			(layer "F.SilkS")
			(effects
				(font
					(size 0.7 0.7)
					(thickness 0.15)
				)
				(justify left bottom)
			)
		)
		(property "Value" "R_0R_0402"
			(at 0 1.4 270)
			(layer "F.Fab")
			(effects
				(font
					(size 0.7 0.7)
					(thickness 0.15)
				)
				(justify left bottom)
			)
		)
		(property "Description" "SMD Chip Resistor, Jumper, 0 ohm, 100 mW, 0402 [1005 Metric], Thick Film, General Purpose"
			(at 0 0 270)
			(layer "F.Fab")
			(hide yes)
			(effects
				(font
					(size 1.27 1.27)
					(thickness 0.15)
				)
			)
		)
		(property "Author" "Antmicro"
			(at 57.19 366.61 0)
			(layer "F.Fab")
			(hide yes)
			(effects
				(font
					(size 1 1)
					(thickness 0.15)
				)
			)
		)
		(property "Current" "1A"
			(at 57.19 366.61 0)
			(layer "F.Fab")
			(hide yes)
			(effects
				(font
					(size 1 1)
					(thickness 0.15)
				)
			)
		)
		(property "License" "Apache-2.0"
			(at 57.19 366.61 0)
			(layer "F.Fab")
			(hide yes)
			(effects
				(font
					(size 1 1)
					(thickness 0.15)
				)
			)
		)
		(property "MPN" "ERJ2GE0R00X"
			(at 57.19 366.61 0)
			(layer "F.Fab")
			(hide yes)
			(effects
				(font
					(size 1 1)
					(thickness 0.15)
				)
			)
		)
		(property "Manufacturer" "Panasonic"
			(at 57.19 366.61 0)
			(layer "F.Fab")
			(hide yes)
			(effects
				(font
					(size 1 1)
					(thickness 0.15)
				)
			)
		)
		(property "Tolerance" ""
			(at 57.19 366.61 0)
			(layer "F.Fab")
			(hide yes)
			(effects
				(font
					(size 1 1)
					(thickness 0.15)
				)
			)
		)
		(property "Val" "0R"
			(at 57.19 366.61 0)
			(layer "F.Fab")
			(hide yes)
			(effects
				(font
					(size 1 1)
					(thickness 0.15)
				)
			)
		)
		(sheetname "SPI Flash + SD Card")
		(sheetfile "spi-flash.kicad_sch")
		(attr smd)
		(fp_rect
			(start -0.925 -0.47)
			(end 0.925 0.47)
			(stroke
				(width 0.05)
				(type default)
			)
			(fill no)
			(layer "F.CrtYd")
		)
		(fp_rect
			(start -0.5 -0.25)
			(end 0.5 0.25)
			(stroke
				(width 0.15)
				(type solid)
			)
			(fill no)
			(layer "F.Fab")
		)
		(pad "1" smd roundrect
			(at -0.48 0 270)
			(size 0.59 0.64)
			(layers "F.Cu" "F.Mask" "F.Paste")
			(roundrect_rratio 0.25)
			(net 402 "/FPGA Bank 33 & 34/USR_FLASH_0.DQ3")
			(pintype "passive")
		)
		(pad "2" smd roundrect
			(at 0.48 0 270)
			(size 0.59 0.64)
			(layers "F.Cu" "F.Mask" "F.Paste")
			(roundrect_rratio 0.25)
			(net 905 "/SPI Flash + SD Card/USR_FLASH_0_DQ3")
			(pintype "passive")
		)
	)
	(footprint "antmicro-footprints:R_0402_1005Metric"
		(layer "F.Cu")
		(at 160 184 -90)
		(descr "Resistor SMD 0402")
		(tags "resistor SMD 0402")
		(property "Reference" "R366"
			(at -0.7 -0.4 270)
			(layer "F.SilkS")
			(effects
				(font
					(size 0.7 0.7)
					(thickness 0.15)
				)
				(justify left bottom)
			)
		)
		(property "Value" "R_0R_0402"
			(at 0 1.4 270)
			(layer "F.Fab")
			(effects
				(font
					(size 0.7 0.7)
					(thickness 0.15)
				)
				(justify left bottom)
			)
		)
		(property "Description" "SMD Chip Resistor, Jumper, 0 ohm, 100 mW, 0402 [1005 Metric], Thick Film, General Purpose"
			(at 0 0 270)
			(layer "F.Fab")
			(hide yes)
			(effects
				(font
					(size 1.27 1.27)
					(thickness 0.15)
				)
			)
		)
		(property "Author" "Antmicro"
			(at -24 344 0)
			(layer "F.Fab")
			(hide yes)
			(effects
				(font
					(size 1 1)
					(thickness 0.15)
				)
			)
		)
		(property "Current" "1A"
			(at -24 344 0)
			(layer "F.Fab")
			(hide yes)
			(effects
				(font
					(size 1 1)
					(thickness 0.15)
				)
			)
		)
		(property "DNP" "DNP"
			(at -24 344 0)
			(layer "F.Fab")
			(hide yes)
			(effects
				(font
					(size 1 1)
					(thickness 0.15)
				)
			)
		)
		(property "License" "Apache-2.0"
			(at -24 344 0)
			(layer "F.Fab")
			(hide yes)
			(effects
				(font
					(size 1 1)
					(thickness 0.15)
				)
			)
		)
		(property "MPN" "ERJ2GE0R00X"
			(at -24 344 0)
			(layer "F.Fab")
			(hide yes)
			(effects
				(font
					(size 1 1)
					(thickness 0.15)
				)
			)
		)
		(property "Manufacturer" "Panasonic"
			(at -24 344 0)
			(layer "F.Fab")
			(hide yes)
			(effects
				(font
					(size 1 1)
					(thickness 0.15)
				)
			)
		)
		(property "Tolerance" ""
			(at -24 344 0)
			(layer "F.Fab")
			(hide yes)
			(effects
				(font
					(size 1 1)
					(thickness 0.15)
				)
			)
		)
		(property "Val" "0R"
			(at -24 344 0)
			(layer "F.Fab")
			(hide yes)
			(effects
				(font
					(size 1 1)
					(thickness 0.15)
				)
			)
		)
		(property "dnp" ""
			(at -24 344 0)
			(layer "F.Fab")
			(hide yes)
			(effects
				(font
					(size 1 1)
					(thickness 0.15)
				)
			)
		)
		(property "exclude_from_bom" ""
			(at -24 344 0)
			(layer "F.Fab")
			(hide yes)
			(effects
				(font
					(size 1 1)
					(thickness 0.15)
				)
			)
		)
		(sheetname "FPGA Bank 12 & 13")
		(sheetfile "fpga-bank-12-13.kicad_sch")
		(attr smd exclude_from_bom)
		(fp_rect
			(start -0.925 -0.47)
			(end 0.925 0.47)
			(stroke
				(width 0.05)
				(type default)
			)
			(fill no)
			(layer "F.CrtYd")
		)
		(fp_rect
			(start -0.5 -0.25)
			(end 0.5 0.25)
			(stroke
				(width 0.15)
				(type solid)
			)
			(fill no)
			(layer "F.Fab")
		)
		(pad "1" smd roundrect
			(at -0.48 0 270)
			(size 0.59 0.64)
			(layers "F.Cu" "F.Mask" "F.Paste")
			(roundrect_rratio 0.25)
			(net 572 "/FPGA Bank 12 & 13/~{PB_CTRL_INT}")
			(pintype "passive")
		)
		(pad "2" smd roundrect
			(at 0.48 0 270)
			(size 0.59 0.64)
			(layers "F.Cu" "F.Mask" "F.Paste")
			(roundrect_rratio 0.25)
			(net 577 "/DC-DC Converters/PB_CTRL.~{PB_CTRL_INT}")
			(pintype "passive")
		)
	)
	(footprint "antmicro-footprints:C_0402_1005Metric"
		(layer "F.Cu")
		(at 171.1 176.1625 90)
		(descr "Capacitor SMD 0402")
		(tags "capacitor SMD 0402")
		(property "Reference" "C334"
			(at -3.6375 0.4 90)
			(layer "F.SilkS")
			(effects
				(font
					(size 0.7 0.7)
					(thickness 0.15)
				)
				(justify left bottom)
			)
		)
		(property "Value" "C_1u_0402"
			(at 0 1.4 90)
			(layer "F.Fab")
			(effects
				(font
					(size 0.7 0.7)
					(thickness 0.15)
				)
				(justify left bottom)
			)
		)
		(property "Description" "SMD Multilayer Ceramic Capacitor, 1 µF, 10 V, 0402 [1005 Metric], ± 10%, X6S, C"
			(at 0 0 90)
			(layer "F.Fab")
			(hide yes)
			(effects
				(font
					(size 1.27 1.27)
					(thickness 0.15)
				)
			)
		)
		(property "Author" "Antmicro"
			(at 347.2625 5.0625 0)
			(layer "F.Fab")
			(hide yes)
			(effects
				(font
					(size 1 1)
					(thickness 0.15)
				)
			)
		)
		(property "DNP" "DNP"
			(at 347.2625 5.0625 0)
			(layer "F.Fab")
			(hide yes)
			(effects
				(font
					(size 1 1)
					(thickness 0.15)
				)
			)
		)
		(property "Dielectric" ""
			(at 347.2625 5.0625 0)
			(layer "F.Fab")
			(hide yes)
			(effects
				(font
					(size 1 1)
					(thickness 0.15)
				)
			)
		)
		(property "License" "Apache-2.0"
			(at 347.2625 5.0625 0)
			(layer "F.Fab")
			(hide yes)
			(effects
				(font
					(size 1 1)
					(thickness 0.15)
				)
			)
		)
		(property "MPN" "C1005X6S1A105K050BC"
			(at 347.2625 5.0625 0)
			(layer "F.Fab")
			(hide yes)
			(effects
				(font
					(size 1 1)
					(thickness 0.15)
				)
			)
		)
		(property "Manufacturer" "TDK"
			(at 347.2625 5.0625 0)
			(layer "F.Fab")
			(hide yes)
			(effects
				(font
					(size 1 1)
					(thickness 0.15)
				)
			)
		)
		(property "Val" "1u"
			(at 347.2625 5.0625 0)
			(layer "F.Fab")
			(hide yes)
			(effects
				(font
					(size 1 1)
					(thickness 0.15)
				)
			)
		)
		(property "Voltage" ""
			(at 347.2625 5.0625 0)
			(layer "F.Fab")
			(hide yes)
			(effects
				(font
					(size 1 1)
					(thickness 0.15)
				)
			)
		)
		(property "dnp" ""
			(at 347.2625 5.0625 0)
			(layer "F.Fab")
			(hide yes)
			(effects
				(font
					(size 1 1)
					(thickness 0.15)
				)
			)
		)
		(property "exclude_from_bom" ""
			(at 347.2625 5.0625 0)
			(layer "F.Fab")
			(hide yes)
			(effects
				(font
					(size 1 1)
					(thickness 0.15)
				)
			)
		)
		(sheetname "DC-DC Converters")
		(sheetfile "dc-dc.kicad_sch")
		(attr smd exclude_from_bom)
		(fp_rect
			(start -0.925 -0.47)
			(end 0.925 0.47)
			(stroke
				(width 0.05)
				(type default)
			)
			(fill no)
			(layer "F.CrtYd")
		)
		(fp_line
			(start 0.504 -0.25)
			(end 0.504 0.248)
			(stroke
				(width 0.15)
				(type solid)
			)
			(layer "F.Fab")
		)
		(fp_line
			(start -0.494 -0.25)
			(end 0.504 -0.25)
			(stroke
				(width 0.15)
				(type solid)
			)
			(layer "F.Fab")
		)
		(fp_line
			(start 0.504 0.248)
			(end -0.494 0.248)
			(stroke
				(width 0.15)
				(type solid)
			)
			(layer "F.Fab")
		)
		(fp_line
			(start -0.494 0.248)
			(end -0.494 -0.25)
			(stroke
				(width 0.15)
				(type solid)
			)
			(layer "F.Fab")
		)
		(pad "1" smd roundrect
			(at -0.48 0 90)
			(size 0.59 0.64)
			(layers "F.Cu" "F.Mask" "F.Paste")
			(roundrect_rratio 0.25)
			(net 1 "GND")
			(pintype "passive")
		)
		(pad "2" smd roundrect
			(at 0.48 0 90)
			(size 0.59 0.64)
			(layers "F.Cu" "F.Mask" "F.Paste")
			(roundrect_rratio 0.25)
			(net 740 "/DC-DC Converters/1V35_local")
			(pintype "passive")
		)
	)
)
